(kicad_pcb
	(version 20260206)
	(generator "pcbnew")
	(generator_version "10.0")
	(general
		(thickness 1.6)
		(legacy_teardrops no)
	)
	(paper "A4")
	(title_block
		(title "01162023_DA0F0TEBIF0_F0T_Expander_BD_F_brd_V02_OCP.brd")
		(comment 1 "Grand Teton / footprints 7905-7911 of 9728")
	)
	(layers
		(0 "F.Cu" signal "TOP")
		(4 "In1.Cu" signal "GND")
		(6 "In2.Cu" signal "VCC")
		(8 "In3.Cu" signal "VCC1")
		(10 "In4.Cu" signal "GND1")
		(12 "In5.Cu" signal "IN1")
		(14 "In6.Cu" signal "GND2")
		(16 "In7.Cu" signal "IN2")
		(18 "In8.Cu" signal "GND3")
		(20 "In9.Cu" signal "IN3")
		(22 "In10.Cu" signal "GND4")
		(24 "In11.Cu" signal "IN4")
		(26 "In12.Cu" signal "GND5")
		(28 "In13.Cu" signal "IN5")
		(30 "In14.Cu" signal "GND6")
		(32 "In15.Cu" signal "IN6")
		(34 "In16.Cu" signal "GND7")
		(2 "B.Cu" signal "BOTTOM")
		(9 "F.Adhes" user "F.Adhesive")
		(11 "B.Adhes" user "B.Adhesive")
		(13 "F.Paste" user "Package Geometry/Pastemask Top")
		(15 "B.Paste" user "Package Geometry/Pastemask Bottom")
		(5 "F.SilkS" user "Ref Des/Silkscreen Top")
		(7 "B.SilkS" user "Ref Des/Silkscreen Bottom")
		(1 "F.Mask" user "Board Geometry/Soldermask Top")
		(3 "B.Mask" user "Board Geometry/Soldermask Bottom")
		(17 "Dwgs.User" user "User.Drawings")
		(19 "Cmts.User" user "User.Comments")
		(21 "Eco1.User" user "User.Eco1")
		(23 "Eco2.User" user "User.Eco2")
		(25 "Edge.Cuts" user "Board Geometry/Outline")
		(27 "Margin" user)
		(31 "F.CrtYd" user "Package Geometry/Place Bound Top")
		(29 "B.CrtYd" user "Package Geometry/Place Bound Bottom")
		(35 "F.Fab" user "Ref Des/Assembly Top")
		(33 "B.Fab" user "Ref Des/Assembly Bottom")
	)
	(footprint ""
		(layer "B.Cu")
		(at 383.683002 -222.590106)
		(property "Reference" "U100"
			(at 1.016 -1.80213 0)
			(unlocked yes)
			(layer "B.SilkS")
			(effects
				(font
					(size 0.7874 0.5842)
					(thickness 0.1524)
				)
				(justify mirror)
			)
		)
		(property "Value" ""
			(at 0 0 0)
			(layer "B.Fab")
			(effects
				(font
					(size 1.27 1.27)
				)
				(justify mirror)
			)
		)
		(duplicate_pad_numbers_are_jumpers no)
		(fp_line
			(start -1.7272 -1.1176)
			(end -1.7272 1.1176)
			(stroke
				(width 0.1524)
				(type default)
			)
			(layer "B.SilkS")
		)
		(fp_line
			(start -1.7272 -1.1176)
			(end -0.254 -1.1176)
			(stroke
				(width 0.1524)
				(type default)
			)
			(layer "B.SilkS")
		)
		(fp_line
			(start -1.7272 1.1176)
			(end 1.7272 1.1176)
			(stroke
				(width 0.1524)
				(type default)
			)
			(layer "B.SilkS")
		)
		(fp_line
			(start -0.254 -1.1176)
			(end 0 -0.7366)
			(stroke
				(width 0.1524)
				(type default)
			)
			(layer "B.SilkS")
		)
		(fp_line
			(start 0 -0.7366)
			(end 0.254 -1.1176)
			(stroke
				(width 0.1524)
				(type default)
			)
			(layer "B.SilkS")
		)
		(fp_line
			(start 0.254 -1.1176)
			(end 1.7272 -1.1176)
			(stroke
				(width 0.1524)
				(type default)
			)
			(layer "B.SilkS")
		)
		(fp_line
			(start 1.7272 1.1176)
			(end 1.7272 -1.1176)
			(stroke
				(width 0.1524)
				(type default)
			)
			(layer "B.SilkS")
		)
		(fp_poly
			(pts
				(xy 1.9558 -0.649986) (xy 2.7178 -0.268986) (xy 2.7178 -1.030986)
			)
			(stroke
				(width 0)
				(type default)
			)
			(fill yes)
			(layer "B.SilkS")
		)
		(fp_line
			(start -1.5748 -1.1176)
			(end 1.5748 -1.1176)
			(stroke
				(width 0.1)
				(type default)
			)
			(layer "B.Fab")
		)
		(fp_line
			(start -1.5748 1.1176)
			(end -1.5748 -1.1176)
			(stroke
				(width 0.1)
				(type default)
			)
			(layer "B.Fab")
		)
		(fp_line
			(start 1.5748 -1.1176)
			(end 1.5748 1.1176)
			(stroke
				(width 0.1)
				(type default)
			)
			(layer "B.Fab")
		)
		(fp_line
			(start 1.5748 1.1176)
			(end -1.5748 1.1176)
			(stroke
				(width 0.1)
				(type default)
			)
			(layer "B.Fab")
		)
		(fp_poly
			(pts
				(xy 1.9558 -0.649986) (xy 2.7178 -0.268986) (xy 2.7178 -1.030986)
			)
			(stroke
				(width 0)
				(type default)
			)
			(fill yes)
			(layer "B.Fab")
		)
		(pad "1" smd rect
			(at 0.999998 -0.649986 270)
			(size 0.3556 1.1176)
			(layers "B.Cu" "B.Mask" "B.Paste")
			(net "UART_PEX0_SDB_R_RX")
		)
		(pad "2" smd rect
			(at 0.999998 0 270)
			(size 0.3556 1.1176)
			(layers "B.Cu" "B.Mask" "B.Paste")
			(net "GND")
		)
		(pad "3" smd rect
			(at 0.999998 0.649986 270)
			(size 0.3556 1.1176)
			(layers "B.Cu" "B.Mask" "B.Paste")
			(net "UART_PEX1_SDB_R_RX")
		)
		(pad "4" smd rect
			(at -0.999998 0.649986 270)
			(size 0.3556 1.1176)
			(layers "B.Cu" "B.Mask" "B.Paste")
			(net "UART_PEX1_SDB_BUF_R_RX")
		)
		(pad "5" smd rect
			(at -0.999998 0 270)
			(size 0.3556 1.1176)
			(layers "B.Cu" "B.Mask" "B.Paste")
			(net "P3V3_AUX")
		)
		(pad "6" smd rect
			(at -0.999998 -0.649986 270)
			(size 0.3556 1.1176)
			(layers "B.Cu" "B.Mask" "B.Paste")
			(net "UART_PEX0_SDB_BUF_R_RX")
		)
	)
	(footprint ""
		(layer "B.Cu")
		(at 256.282952 -220.932756 90)
		(property "Reference" "R3479"
			(at 0 0 90)
			(layer "B.SilkS")
			(hide yes)
			(effects
				(font
					(size 1.27 1.27)
				)
				(justify mirror)
			)
		)
		(property "Value" ""
			(at 0 0 90)
			(layer "B.Fab")
			(effects
				(font
					(size 1.27 1.27)
				)
				(justify mirror)
			)
		)
		(duplicate_pad_numbers_are_jumpers no)
		(fp_line
			(start 0.7874 -0.4064)
			(end -0.7874 -0.4064)
			(stroke
				(width 0.1524)
				(type default)
			)
			(layer "B.SilkS")
		)
		(fp_line
			(start -0.7874 -0.4064)
			(end -0.7874 0.4064)
			(stroke
				(width 0.1524)
				(type default)
			)
			(layer "B.SilkS")
		)
		(fp_line
			(start 0.7874 0.4064)
			(end 0.7874 -0.4064)
			(stroke
				(width 0.1524)
				(type default)
			)
			(layer "B.SilkS")
		)
		(fp_line
			(start -0.7874 0.4064)
			(end 0.7874 0.4064)
			(stroke
				(width 0.1524)
				(type default)
			)
			(layer "B.SilkS")
		)
		(fp_line
			(start 0.67945 -0.305054)
			(end 0.12065 -0.305054)
			(stroke
				(width 0.1)
				(type default)
			)
			(layer "B.Fab")
		)
		(fp_line
			(start 0.12065 -0.305054)
			(end 0.12065 -0.2794)
			(stroke
				(width 0.1)
				(type default)
			)
			(layer "B.Fab")
		)
		(fp_line
			(start -0.12065 -0.3048)
			(end -0.67945 -0.3048)
			(stroke
				(width 0.1)
				(type default)
			)
			(layer "B.Fab")
		)
		(fp_line
			(start -0.67945 -0.3048)
			(end -0.67945 0.3048)
			(stroke
				(width 0.1)
				(type default)
			)
			(layer "B.Fab")
		)
		(fp_line
			(start 0.12065 -0.2794)
			(end -0.12065 -0.2794)
			(stroke
				(width 0.1)
				(type default)
			)
			(layer "B.Fab")
		)
		(fp_line
			(start -0.12065 -0.2794)
			(end -0.12065 -0.3048)
			(stroke
				(width 0.1)
				(type default)
			)
			(layer "B.Fab")
		)
		(fp_line
			(start 0.12065 0.2794)
			(end 0.12065 0.3048)
			(stroke
				(width 0.1)
				(type default)
			)
			(layer "B.Fab")
		)
		(fp_line
			(start -0.120396 0.2794)
			(end 0.12065 0.2794)
			(stroke
				(width 0.1)
				(type default)
			)
			(layer "B.Fab")
		)
		(fp_line
			(start 0.67945 0.3048)
			(end 0.67945 -0.305054)
			(stroke
				(width 0.1)
				(type default)
			)
			(layer "B.Fab")
		)
		(fp_line
			(start 0.12065 0.3048)
			(end 0.67945 0.3048)
			(stroke
				(width 0.1)
				(type default)
			)
			(layer "B.Fab")
		)
		(fp_line
			(start -0.120396 0.3048)
			(end -0.120396 0.2794)
			(stroke
				(width 0.1)
				(type default)
			)
			(layer "B.Fab")
		)
		(fp_line
			(start -0.67945 0.3048)
			(end -0.120396 0.3048)
			(stroke
				(width 0.1)
				(type default)
			)
			(layer "B.Fab")
		)
		(pad "1" smd circle
			(at 0.40005 0 270)
			(size 0 0)
			(layers "B.Cu" "B.Mask" "B.Paste")
			(net "SPI_PEX2_SDIO3_R")
		)
		(pad "2" smd circle
			(at -0.40005 0 270)
			(size 0 0)
			(layers "B.Cu" "B.Mask" "B.Paste")
			(net "SPI_PEX2_SDIO3_R1")
		)
	)
	(footprint ""
		(layer "B.Cu")
		(at 64.874902 -286.399732 90)
		(property "Reference" "C2965"
			(at 0 0 90)
			(layer "B.SilkS")
			(hide yes)
			(effects
				(font
					(size 1.27 1.27)
				)
				(justify mirror)
			)
		)
		(property "Value" ""
			(at 0 0 90)
			(layer "B.Fab")
			(effects
				(font
					(size 1.27 1.27)
				)
				(justify mirror)
			)
		)
		(duplicate_pad_numbers_are_jumpers no)
		(fp_line
			(start 0.299974 -0.150114)
			(end -0.299974 -0.150114)
			(stroke
				(width 0.1)
				(type default)
			)
			(layer "B.Fab")
		)
		(fp_line
			(start -0.299974 -0.150114)
			(end -0.299974 0.150114)
			(stroke
				(width 0.1)
				(type default)
			)
			(layer "B.Fab")
		)
		(fp_line
			(start 0.299974 0.150114)
			(end 0.299974 -0.150114)
			(stroke
				(width 0.1)
				(type default)
			)
			(layer "B.Fab")
		)
		(fp_line
			(start -0.299974 0.150114)
			(end 0.299974 0.150114)
			(stroke
				(width 0.1)
				(type default)
			)
			(layer "B.Fab")
		)
		(pad "1" smd rect
			(at 0.2667 0 270)
			(size 0.3048 0.381)
			(layers "B.Cu" "B.Mask" "B.Paste")
			(net "P1V25_SERDES_VDDPLL_PEX0")
		)
		(pad "2" smd rect
			(at -0.2667 0 270)
			(size 0.3048 0.381)
			(layers "B.Cu" "B.Mask" "B.Paste")
			(net "GND")
		)
	)
	(footprint ""
		(layer "B.Cu")
		(at 281.399742 -290.674806 180)
		(property "Reference" "C1614"
			(at 0 0 0)
			(layer "B.SilkS")
			(hide yes)
			(effects
				(font
					(size 1.27 1.27)
				)
				(justify mirror)
			)
		)
		(property "Value" ""
			(at 0 0 0)
			(layer "B.Fab")
			(effects
				(font
					(size 1.27 1.27)
				)
				(justify mirror)
			)
		)
		(duplicate_pad_numbers_are_jumpers no)
		(fp_line
			(start 0.299974 0.150114)
			(end 0.299974 -0.150114)
			(stroke
				(width 0.1)
				(type default)
			)
			(layer "B.Fab")
		)
		(fp_line
			(start 0.299974 -0.150114)
			(end -0.299974 -0.150114)
			(stroke
				(width 0.1)
				(type default)
			)
			(layer "B.Fab")
		)
		(fp_line
			(start -0.299974 0.150114)
			(end 0.299974 0.150114)
			(stroke
				(width 0.1)
				(type default)
			)
			(layer "B.Fab")
		)
		(fp_line
			(start -0.299974 -0.150114)
			(end -0.299974 0.150114)
			(stroke
				(width 0.1)
				(type default)
			)
			(layer "B.Fab")
		)
		(pad "1" smd rect
			(at 0.2667 0)
			(size 0.3048 0.381)
			(layers "B.Cu" "B.Mask" "B.Paste")
			(net "P0V8_PEX2")
		)
		(pad "2" smd rect
			(at -0.2667 0)
			(size 0.3048 0.381)
			(layers "B.Cu" "B.Mask" "B.Paste")
			(net "GND")
		)
	)
	(footprint ""
		(layer "B.Cu")
		(at 259.16763 -87.046054 90)
		(property "Reference" "C2646"
			(at 0 0 90)
			(layer "B.SilkS")
			(hide yes)
			(effects
				(font
					(size 1.27 1.27)
				)
				(justify mirror)
			)
		)
		(property "Value" ""
			(at 0 0 90)
			(layer "B.Fab")
			(effects
				(font
					(size 1.27 1.27)
				)
				(justify mirror)
			)
		)
		(duplicate_pad_numbers_are_jumpers no)
		(fp_line
			(start 0.7874 -0.4064)
			(end -0.7874 -0.4064)
			(stroke
				(width 0.1524)
				(type default)
			)
			(layer "B.SilkS")
		)
		(fp_line
			(start -0.7874 -0.4064)
			(end -0.7874 0.4064)
			(stroke
				(width 0.1524)
				(type default)
			)
			(layer "B.SilkS")
		)
		(fp_line
			(start 0.7874 0.4064)
			(end 0.7874 -0.4064)
			(stroke
				(width 0.1524)
				(type default)
			)
			(layer "B.SilkS")
		)
		(fp_line
			(start -0.7874 0.4064)
			(end 0.7874 0.4064)
			(stroke
				(width 0.1524)
				(type default)
			)
			(layer "B.SilkS")
		)
		(fp_line
			(start 0.67945 -0.305054)
			(end 0.12065 -0.305054)
			(stroke
				(width 0.1)
				(type default)
			)
			(layer "B.Fab")
		)
		(fp_line
			(start 0.12065 -0.305054)
			(end 0.12065 -0.2794)
			(stroke
				(width 0.1)
				(type default)
			)
			(layer "B.Fab")
		)
		(fp_line
			(start -0.12065 -0.3048)
			(end -0.67945 -0.3048)
			(stroke
				(width 0.1)
				(type default)
			)
			(layer "B.Fab")
		)
		(fp_line
			(start -0.67945 -0.3048)
			(end -0.67945 0.3048)
			(stroke
				(width 0.1)
				(type default)
			)
			(layer "B.Fab")
		)
		(fp_line
			(start 0.12065 -0.2794)
			(end -0.12065 -0.2794)
			(stroke
				(width 0.1)
				(type default)
			)
			(layer "B.Fab")
		)
		(fp_line
			(start -0.12065 -0.2794)
			(end -0.12065 -0.3048)
			(stroke
				(width 0.1)
				(type default)
			)
			(layer "B.Fab")
		)
		(fp_line
			(start 0.12065 0.2794)
			(end 0.12065 0.3048)
			(stroke
				(width 0.1)
				(type default)
			)
			(layer "B.Fab")
		)
		(fp_line
			(start -0.120396 0.2794)
			(end 0.12065 0.2794)
			(stroke
				(width 0.1)
				(type default)
			)
			(layer "B.Fab")
		)
		(fp_line
			(start 0.67945 0.3048)
			(end 0.67945 -0.305054)
			(stroke
				(width 0.1)
				(type default)
			)
			(layer "B.Fab")
		)
		(fp_line
			(start 0.12065 0.3048)
			(end 0.67945 0.3048)
			(stroke
				(width 0.1)
				(type default)
			)
			(layer "B.Fab")
		)
		(fp_line
			(start -0.120396 0.3048)
			(end -0.120396 0.2794)
			(stroke
				(width 0.1)
				(type default)
			)
			(layer "B.Fab")
		)
		(fp_line
			(start -0.67945 0.3048)
			(end -0.120396 0.3048)
			(stroke
				(width 0.1)
				(type default)
			)
			(layer "B.Fab")
		)
		(pad "1" smd circle
			(at 0.40005 0 270)
			(size 0 0)
			(layers "B.Cu" "B.Mask" "B.Paste")
			(net "P3V3_CLK_GEN_VDDMXCK_CK440")
		)
		(pad "2" smd circle
			(at -0.40005 0 270)
			(size 0 0)
			(layers "B.Cu" "B.Mask" "B.Paste")
			(net "GND")
		)
	)
	(footprint ""
		(layer "B.Cu")
		(at 343.289382 -284.796738 -90)
		(property "Reference" "PC161"
			(at 0 0 90)
			(layer "B.SilkS")
			(hide yes)
			(effects
				(font
					(size 1.27 1.27)
				)
				(justify mirror)
			)
		)
		(property "Value" ""
			(at 0 0 90)
			(layer "B.Fab")
			(effects
				(font
					(size 1.27 1.27)
				)
				(justify mirror)
			)
		)
		(duplicate_pad_numbers_are_jumpers no)
		(fp_line
			(start -1.524 0.762)
			(end 1.524 0.762)
			(stroke
				(width 0.1524)
				(type default)
			)
			(layer "B.SilkS")
		)
		(fp_line
			(start 1.524 0.762)
			(end 1.524 -0.762)
			(stroke
				(width 0.1524)
				(type default)
			)
			(layer "B.SilkS")
		)
		(fp_line
			(start -1.524 -0.762)
			(end -1.524 0.762)
			(stroke
				(width 0.1524)
				(type default)
			)
			(layer "B.SilkS")
		)
		(fp_line
			(start 1.524 -0.762)
			(end -1.524 -0.762)
			(stroke
				(width 0.1524)
				(type default)
			)
			(layer "B.SilkS")
		)
		(fp_line
			(start -1.1049 0.724916)
			(end -1.1049 -0.724916)
			(stroke
				(width 0.1)
				(type default)
			)
			(layer "B.Fab")
		)
		(fp_line
			(start 1.1049 0.724916)
			(end -1.1049 0.724916)
			(stroke
				(width 0.1)
				(type default)
			)
			(layer "B.Fab")
		)
		(fp_line
			(start -1.1049 -0.724916)
			(end 1.1049 -0.724916)
			(stroke
				(width 0.1)
				(type default)
			)
			(layer "B.Fab")
		)
		(fp_line
			(start 1.1049 -0.724916)
			(end 1.1049 0.724916)
			(stroke
				(width 0.1)
				(type default)
			)
			(layer "B.Fab")
		)
		(pad "1" smd rect
			(at 0.889 0 270)
			(size 1.016 1.27)
			(layers "B.Cu" "B.Mask" "B.Paste")
			(net "SW_P12V_P0V8_PEX2_FLT")
		)
		(pad "2" smd rect
			(at -0.889 0 270)
			(size 1.016 1.27)
			(layers "B.Cu" "B.Mask" "B.Paste")
			(net "GND")
		)
	)
	(footprint ""
		(layer "B.Cu")
		(at 129.486914 -182.604664 90)
		(property "Reference" "R1122"
			(at 0 0 90)
			(layer "B.SilkS")
			(hide yes)
			(effects
				(font
					(size 1.27 1.27)
				)
				(justify mirror)
			)
		)
		(property "Value" ""
			(at 0 0 90)
			(layer "B.Fab")
			(effects
				(font
					(size 1.27 1.27)
				)
				(justify mirror)
			)
		)
		(duplicate_pad_numbers_are_jumpers no)
		(fp_line
			(start 0.7874 -0.4064)
			(end -0.7874 -0.4064)
			(stroke
				(width 0.1524)
				(type default)
			)
			(layer "B.SilkS")
		)
		(fp_line
			(start -0.7874 -0.4064)
			(end -0.7874 0.4064)
			(stroke
				(width 0.1524)
				(type default)
			)
			(layer "B.SilkS")
		)
		(fp_line
			(start 0.7874 0.4064)
			(end 0.7874 -0.4064)
			(stroke
				(width 0.1524)
				(type default)
			)
			(layer "B.SilkS")
		)
		(fp_line
			(start -0.7874 0.4064)
			(end 0.7874 0.4064)
			(stroke
				(width 0.1524)
				(type default)
			)
			(layer "B.SilkS")
		)
		(fp_line
			(start 0.67945 -0.305054)
			(end 0.12065 -0.305054)
			(stroke
				(width 0.1)
				(type default)
			)
			(layer "B.Fab")
		)
		(fp_line
			(start 0.12065 -0.305054)
			(end 0.12065 -0.2794)
			(stroke
				(width 0.1)
				(type default)
			)
			(layer "B.Fab")
		)
		(fp_line
			(start -0.12065 -0.3048)
			(end -0.67945 -0.3048)
			(stroke
				(width 0.1)
				(type default)
			)
			(layer "B.Fab")
		)
		(fp_line
			(start -0.67945 -0.3048)
			(end -0.67945 0.3048)
			(stroke
				(width 0.1)
				(type default)
			)
			(layer "B.Fab")
		)
		(fp_line
			(start 0.12065 -0.2794)
			(end -0.12065 -0.2794)
			(stroke
				(width 0.1)
				(type default)
			)
			(layer "B.Fab")
		)
		(fp_line
			(start -0.12065 -0.2794)
			(end -0.12065 -0.3048)
			(stroke
				(width 0.1)
				(type default)
			)
			(layer "B.Fab")
		)
		(fp_line
			(start 0.12065 0.2794)
			(end 0.12065 0.3048)
			(stroke
				(width 0.1)
				(type default)
			)
			(layer "B.Fab")
		)
		(fp_line
			(start -0.120396 0.2794)
			(end 0.12065 0.2794)
			(stroke
				(width 0.1)
				(type default)
			)
			(layer "B.Fab")
		)
		(fp_line
			(start 0.67945 0.3048)
			(end 0.67945 -0.305054)
			(stroke
				(width 0.1)
				(type default)
			)
			(layer "B.Fab")
		)
		(fp_line
			(start 0.12065 0.3048)
			(end 0.67945 0.3048)
			(stroke
				(width 0.1)
				(type default)
			)
			(layer "B.Fab")
		)
		(fp_line
			(start -0.120396 0.3048)
			(end -0.120396 0.2794)
			(stroke
				(width 0.1)
				(type default)
			)
			(layer "B.Fab")
		)
		(fp_line
			(start -0.67945 0.3048)
			(end -0.120396 0.3048)
			(stroke
				(width 0.1)
				(type default)
			)
			(layer "B.Fab")
		)
		(pad "1" smd circle
			(at 0.40005 0 270)
			(size 0 0)
			(layers "B.Cu" "B.Mask" "B.Paste")
			(net "GND")
		)
		(pad "2" smd circle
			(at -0.40005 0 270)
			(size 0 0)
			(layers "B.Cu" "B.Mask" "B.Paste")
			(net "FM_DB2000QL_SMB_SA0")
		)
	)
)
